(kicad_pcb
	(version 20260206)
	(generator "pcbnew")
	(generator_version "10.0")
	(general
		(thickness 1.6)
		(legacy_teardrops no)
	)
	(paper "A4")
	(title_block
		(title "Bryce Canyon_R.DPB_16317-1_OCP.brd")
		(comment 1 "Bryce Canyon / footprints 1653-1659 of 2099")
	)
	(layers
		(0 "F.Cu" signal "TOP")
		(4 "In1.Cu" signal "L2GND")
		(6 "In2.Cu" signal "L3")
		(8 "In3.Cu" signal "L4VCC")
		(10 "In4.Cu" signal "L5VCC")
		(12 "In5.Cu" signal "L6")
		(14 "In6.Cu" signal "L7GND")
		(2 "B.Cu" signal "BOTTOM")
		(9 "F.Adhes" user "F.Adhesive")
		(11 "B.Adhes" user "B.Adhesive")
		(13 "F.Paste" user "Package Geometry/Pastemask Top")
		(15 "B.Paste" user "Package Geometry/Pastemask Bottom")
		(5 "F.SilkS" user "Ref Des/Silkscreen Top")
		(7 "B.SilkS" user "Ref Des/Silkscreen Bottom")
		(1 "F.Mask" user "Board Geometry/Soldermask Top")
		(3 "B.Mask" user "Board Geometry/Soldermask Bottom")
		(17 "Dwgs.User" user "User.Drawings")
		(19 "Cmts.User" user "User.Comments")
		(21 "Eco1.User" user "User.Eco1")
		(23 "Eco2.User" user "User.Eco2")
		(25 "Edge.Cuts" user "Board Geometry/Outline")
		(27 "Margin" user)
		(31 "F.CrtYd" user "Package Geometry/Place Bound Top")
		(29 "B.CrtYd" user "Package Geometry/Place Bound Bottom")
		(35 "F.Fab" user "Ref Des/Assembly Top")
		(33 "B.Fab" user "Ref Des/Assembly Bottom")
	)
	(footprint ""
		(layer "F.Cu")
		(at 457.708 -249.4788 90)
		(property "Reference" "R323"
			(at 0 0 90)
			(layer "F.SilkS")
			(hide yes)
			(effects
				(font
					(size 1.27 1.27)
				)
			)
		)
		(property "Value" "4K7R2J-2-GP"
			(at 0.064008 -3.993896 90)
			(unlocked yes)
			(layer "F.Fab")
			(hide yes)
			(effects
				(font
					(size 1.016 1.016)
					(thickness 0.1524)
				)
			)
		)
		(property "Device Type" "R402H16"
			(at 0.064008 -5.517896 90)
			(unlocked yes)
			(layer "F.Fab")
			(hide yes)
			(effects
				(font
					(size 1.016 1.016)
					(thickness 0.1524)
				)
			)
		)
		(duplicate_pad_numbers_are_jumpers no)
		(fp_line
			(start 0.508 -0.9398)
			(end -0.508 -0.9398)
			(stroke
				(width 0.1524)
				(type default)
			)
			(layer "F.SilkS")
		)
		(fp_line
			(start -0.508 -0.9398)
			(end -0.508 0.9398)
			(stroke
				(width 0.1524)
				(type default)
			)
			(layer "F.SilkS")
		)
		(fp_rect
			(start -0.508 0.9398)
			(end 0.508 -0.9398)
			(stroke
				(width 0)
				(type default)
			)
			(fill no)
			(layer "F.CrtYd")
		)
		(fp_rect
			(start -0.508 0.9398)
			(end 0.508 -0.9398)
			(stroke
				(width 0)
				(type default)
			)
			(fill no)
			(layer "F.Fab")
		)
		(pad "1" smd custom
			(at 0 -0.4445 90)
			(size 0.1397 0.1397)
			(layers "F.Cu" "F.Mask" "F.Paste")
			(net "P12V_B")
			(options
				(clearance outline)
				(anchor circle)
			)
			(primitives
				(gr_poly
					(pts
						(arc
							(start -0.1778 -0.2794)
							(mid -0.249642 -0.249642)
							(end -0.2794 -0.1778)
						)
						(arc
							(start -0.2794 0.1778)
							(mid -0.249642 0.249642)
							(end -0.1778 0.2794)
						)
						(arc
							(start 0.1778 0.2794)
							(mid 0.249642 0.249642)
							(end 0.2794 0.1778)
						)
						(arc
							(start 0.2794 -0.1778)
							(mid 0.249642 -0.249642)
							(end 0.1778 -0.2794)
						)
					)
					(width 0)
					(fill yes)
				)
			)
		)
		(pad "2" smd custom
			(at 0 0.4445 90)
			(size 0.1397 0.1397)
			(layers "F.Cu" "F.Mask" "F.Paste")
			(net "SW_HDD_P10")
			(options
				(clearance outline)
				(anchor circle)
			)
			(primitives
				(gr_poly
					(pts
						(arc
							(start -0.1778 -0.2794)
							(mid -0.249642 -0.249642)
							(end -0.2794 -0.1778)
						)
						(arc
							(start -0.2794 0.1778)
							(mid -0.249642 0.249642)
							(end -0.1778 0.2794)
						)
						(arc
							(start 0.1778 0.2794)
							(mid 0.249642 0.249642)
							(end 0.2794 0.1778)
						)
						(arc
							(start 0.2794 -0.1778)
							(mid 0.249642 -0.249642)
							(end 0.1778 -0.2794)
						)
					)
					(width 0)
					(fill yes)
				)
			)
		)
	)
	(footprint ""
		(layer "F.Cu")
		(at 447.834512 -129.66065 -90)
		(property "Reference" "C315"
			(at 0 0 270)
			(layer "F.SilkS")
			(hide yes)
			(effects
				(font
					(size 1.27 1.27)
				)
			)
		)
		(property "Value" "SCD01U16V1KX-GP"
			(at -2.8321 -1.7399 270)
			(unlocked yes)
			(layer "F.Fab")
			(hide yes)
			(effects
				(font
					(size 1.016 1.016)
					(thickness 0.1524)
				)
			)
		)
		(property "Device Type" "C0201H13"
			(at -2.8321 -3.2639 270)
			(unlocked yes)
			(layer "F.Fab")
			(hide yes)
			(effects
				(font
					(size 1.016 1.016)
					(thickness 0.1524)
				)
			)
		)
		(duplicate_pad_numbers_are_jumpers no)
		(fp_rect
			(start -0.2794 0.6477)
			(end 0.2794 -0.6477)
			(stroke
				(width 0)
				(type default)
			)
			(fill no)
			(layer "F.CrtYd")
		)
		(fp_rect
			(start -0.2794 0.6477)
			(end 0.2794 -0.6477)
			(stroke
				(width 0)
				(type default)
			)
			(fill no)
			(layer "F.Fab")
		)
		(pad "1" smd custom
			(at 0 -0.2794 270)
			(size 0.0762 0.0762)
			(layers "F.Cu" "F.Mask" "F.Paste")
			(net "SAS_HDD_RX_P22")
			(options
				(clearance outline)
				(anchor circle)
			)
			(primitives
				(gr_poly
					(pts
						(arc
							(start 0.1524 -0.127)
							(mid 0.137521 -0.162921)
							(end 0.1016 -0.1778)
						)
						(arc
							(start -0.1016 -0.1778)
							(mid -0.137521 -0.162921)
							(end -0.1524 -0.127)
						)
						(arc
							(start -0.1524 0.127)
							(mid -0.137521 0.162921)
							(end -0.1016 0.1778)
						)
						(arc
							(start 0.1016 0.1778)
							(mid 0.137521 0.162921)
							(end 0.1524 0.127)
						)
					)
					(width 0)
					(fill yes)
				)
			)
		)
		(pad "2" smd custom
			(at 0 0.2794 270)
			(size 0.0762 0.0762)
			(layers "F.Cu" "F.Mask" "F.Paste")
			(net "PHY_SCC_B_TO_DRV_B_22_DP")
			(options
				(clearance outline)
				(anchor circle)
			)
			(primitives
				(gr_poly
					(pts
						(arc
							(start 0.1524 -0.127)
							(mid 0.137521 -0.162921)
							(end 0.1016 -0.1778)
						)
						(arc
							(start -0.1016 -0.1778)
							(mid -0.137521 -0.162921)
							(end -0.1524 -0.127)
						)
						(arc
							(start -0.1524 0.127)
							(mid -0.137521 0.162921)
							(end -0.1016 0.1778)
						)
						(arc
							(start 0.1016 0.1778)
							(mid 0.137521 0.162921)
							(end 0.1524 0.127)
						)
					)
					(width 0)
					(fill yes)
				)
			)
		)
	)
	(footprint ""
		(layer "F.Cu")
		(at 51.943 -134.493 180)
		(property "Reference" "Q53"
			(at 0 0 180)
			(layer "F.SilkS")
			(hide yes)
			(effects
				(font
					(size 1.27 1.27)
				)
			)
		)
		(property "Value" "2N7002KDW-GP"
			(at -2.3622 -8.2042 180)
			(unlocked yes)
			(layer "F.Fab")
			(hide yes)
			(effects
				(font
					(size 1.016 1.016)
					(thickness 0.1524)
				)
			)
		)
		(property "Device Type" "SOT-363H44"
			(at -2.3622 -10.1092 180)
			(unlocked yes)
			(layer "F.Fab")
			(hide yes)
			(effects
				(font
					(size 1.016 1.016)
					(thickness 0.1524)
				)
			)
		)
		(duplicate_pad_numbers_are_jumpers no)
		(fp_line
			(start 1.4478 1.7018)
			(end 1.4478 -1.7018)
			(stroke
				(width 0.1524)
				(type default)
			)
			(layer "F.SilkS")
		)
		(fp_line
			(start 1.4478 -1.7018)
			(end -1.4478 -1.7018)
			(stroke
				(width 0.1524)
				(type default)
			)
			(layer "F.SilkS")
		)
		(fp_line
			(start -1.27 1.524)
			(end -1.27 0.6604)
			(stroke
				(width 0.4826)
				(type default)
			)
			(layer "F.SilkS")
		)
		(fp_line
			(start -1.4478 1.7018)
			(end 1.4478 1.7018)
			(stroke
				(width 0.1524)
				(type default)
			)
			(layer "F.SilkS")
		)
		(fp_line
			(start -1.4478 -1.7018)
			(end -1.4478 1.7018)
			(stroke
				(width 0.1524)
				(type default)
			)
			(layer "F.SilkS")
		)
		(fp_poly
			(pts
				(xy -1.524 -1.778) (xy 1.524 -1.778) (xy 1.524 1.778) (xy -1.524 1.778)
			)
			(stroke
				(width 0)
				(type default)
			)
			(fill no)
			(layer "F.CrtYd")
		)
		(fp_poly
			(pts
				(xy -1.524 -1.778) (xy 1.524 -1.778) (xy 1.524 1.778) (xy -1.524 1.778)
			)
			(stroke
				(width 0)
				(type default)
			)
			(fill no)
			(layer "F.Fab")
		)
		(pad "1" smd rect
			(at -0.65024 0.9398 180)
			(size 0.4064 1.016)
			(layers "F.Cu" "F.Mask" "F.Paste")
			(net "GND")
		)
		(pad "2" smd rect
			(at 0 0.9398 180)
			(size 0.4064 1.016)
			(layers "F.Cu" "F.Mask" "F.Paste")
			(net "SW_PWR_R_HDD13")
		)
		(pad "3" smd rect
			(at 0.65024 0.9398 180)
			(size 0.4064 1.016)
			(layers "F.Cu" "F.Mask" "F.Paste")
			(net "SW_HDD_P13")
		)
		(pad "4" smd rect
			(at 0.65024 -0.9398 180)
			(size 0.4064 1.016)
			(layers "F.Cu" "F.Mask" "F.Paste")
			(net "GND")
		)
		(pad "5" smd rect
			(at 0 -0.9398 180)
			(size 0.4064 1.016)
			(layers "F.Cu" "F.Mask" "F.Paste")
			(net "SW_HDD_G13")
		)
		(pad "6" smd rect
			(at -0.65024 -0.9398 180)
			(size 0.4064 1.016)
			(layers "F.Cu" "F.Mask" "F.Paste")
			(net "SW_HDD_R13")
		)
	)
	(footprint ""
		(layer "F.Cu")
		(at 77.5716 -214.757 180)
		(property "Reference" "Q221"
			(at 0 0 180)
			(layer "F.SilkS")
			(hide yes)
			(effects
				(font
					(size 1.27 1.27)
				)
			)
		)
		(property "Value" "2N7002K-2-GP"
			(at 0.127 -8.9662 180)
			(unlocked yes)
			(layer "F.Fab")
			(hide yes)
			(effects
				(font
					(size 1.016 1.016)
					(thickness 0.1524)
				)
			)
		)
		(property "Device Type" "SOT23DGS2D4H44"
			(at 0.127 -10.4902 180)
			(unlocked yes)
			(layer "F.Fab")
			(hide yes)
			(effects
				(font
					(size 1.016 1.016)
					(thickness 0.1524)
				)
			)
		)
		(duplicate_pad_numbers_are_jumpers no)
		(fp_line
			(start 1.651 1.778)
			(end 1.651 -1.778)
			(stroke
				(width 0.1524)
				(type default)
			)
			(layer "F.SilkS")
		)
		(fp_line
			(start 1.651 -1.778)
			(end -1.651 -1.778)
			(stroke
				(width 0.1524)
				(type default)
			)
			(layer "F.SilkS")
		)
		(fp_line
			(start -1.651 1.778)
			(end 1.651 1.778)
			(stroke
				(width 0.1524)
				(type default)
			)
			(layer "F.SilkS")
		)
		(fp_line
			(start -1.651 -1.778)
			(end -1.651 1.778)
			(stroke
				(width 0.1524)
				(type default)
			)
			(layer "F.SilkS")
		)
		(fp_poly
			(pts
				(xy -1.778 1.8796) (xy -1.778 -1.8796) (xy 1.778 -1.8796) (xy 1.778 1.8796)
			)
			(stroke
				(width 0)
				(type default)
			)
			(fill no)
			(layer "F.CrtYd")
		)
		(fp_poly
			(pts
				(xy -1.778 1.8796) (xy -1.778 -1.8796) (xy 1.778 -1.8796) (xy 1.778 1.8796)
			)
			(stroke
				(width 0)
				(type default)
			)
			(fill no)
			(layer "F.Fab")
		)
		(pad "D" smd custom
			(at 0 -0.9525 180)
			(size 0.1905 0.1905)
			(layers "F.Cu" "F.Mask" "F.Paste")
			(net "FLT_HDD2_N")
			(options
				(clearance outline)
				(anchor circle)
			)
			(primitives
				(gr_poly
					(pts
						(arc
							(start -0.1778 0.5715)
							(mid -0.321484 0.511984)
							(end -0.381 0.3683)
						)
						(arc
							(start -0.381 -0.3683)
							(mid -0.321484 -0.511984)
							(end -0.1778 -0.5715)
						)
						(arc
							(start 0.1778 -0.5715)
							(mid 0.321484 -0.511984)
							(end 0.381 -0.3683)
						)
						(arc
							(start 0.381 0.3683)
							(mid 0.321484 0.511984)
							(end 0.1778 0.5715)
						)
					)
					(width 0)
					(fill yes)
				)
			)
		)
		(pad "G" smd custom
			(at -0.98425 0.9525 180)
			(size 0.1905 0.1905)
			(layers "F.Cu" "F.Mask" "F.Paste")
			(net "DRIVE_B_2_FLT_LED")
			(options
				(clearance outline)
				(anchor circle)
			)
			(primitives
				(gr_poly
					(pts
						(arc
							(start -0.1778 0.5715)
							(mid -0.321484 0.511984)
							(end -0.381 0.3683)
						)
						(arc
							(start -0.381 -0.3683)
							(mid -0.321484 -0.511984)
							(end -0.1778 -0.5715)
						)
						(arc
							(start 0.1778 -0.5715)
							(mid 0.321484 -0.511984)
							(end 0.381 -0.3683)
						)
						(arc
							(start 0.381 0.3683)
							(mid 0.321484 0.511984)
							(end 0.1778 0.5715)
						)
					)
					(width 0)
					(fill yes)
				)
			)
		)
		(pad "S" smd custom
			(at 0.98425 0.9525 180)
			(size 0.1905 0.1905)
			(layers "F.Cu" "F.Mask" "F.Paste")
			(net "GND")
			(options
				(clearance outline)
				(anchor circle)
			)
			(primitives
				(gr_poly
					(pts
						(arc
							(start -0.1778 0.5715)
							(mid -0.321484 0.511984)
							(end -0.381 0.3683)
						)
						(arc
							(start -0.381 -0.3683)
							(mid -0.321484 -0.511984)
							(end -0.1778 -0.5715)
						)
						(arc
							(start 0.1778 -0.5715)
							(mid 0.321484 -0.511984)
							(end 0.381 -0.3683)
						)
						(arc
							(start 0.381 0.3683)
							(mid 0.321484 0.511984)
							(end 0.1778 0.5715)
						)
					)
					(width 0)
					(fill yes)
				)
			)
		)
	)
	(footprint ""
		(layer "F.Cu")
		(at 149.225 -134.493 90)
		(property "Reference" "R451"
			(at 0 0 90)
			(layer "F.SilkS")
			(hide yes)
			(effects
				(font
					(size 1.27 1.27)
				)
			)
		)
		(property "Value" "4K7R2F-GP"
			(at 0.064008 -3.993896 90)
			(unlocked yes)
			(layer "F.Fab")
			(hide yes)
			(effects
				(font
					(size 1.016 1.016)
					(thickness 0.1524)
				)
			)
		)
		(property "Device Type" "R402H16"
			(at 0.064008 -5.517896 90)
			(unlocked yes)
			(layer "F.Fab")
			(hide yes)
			(effects
				(font
					(size 1.016 1.016)
					(thickness 0.1524)
				)
			)
		)
		(duplicate_pad_numbers_are_jumpers no)
		(fp_line
			(start 0.508 -0.9398)
			(end -0.508 -0.9398)
			(stroke
				(width 0.1524)
				(type default)
			)
			(layer "F.SilkS")
		)
		(fp_line
			(start -0.508 -0.9398)
			(end -0.508 0.9398)
			(stroke
				(width 0.1524)
				(type default)
			)
			(layer "F.SilkS")
		)
		(fp_rect
			(start -0.508 0.9398)
			(end 0.508 -0.9398)
			(stroke
				(width 0)
				(type default)
			)
			(fill no)
			(layer "F.CrtYd")
		)
		(fp_rect
			(start -0.508 0.9398)
			(end 0.508 -0.9398)
			(stroke
				(width 0)
				(type default)
			)
			(fill no)
			(layer "F.Fab")
		)
		(pad "1" smd custom
			(at 0 -0.4445 90)
			(size 0.1397 0.1397)
			(layers "F.Cu" "F.Mask" "F.Paste")
			(net "SW_PWR_R_HDD16")
			(options
				(clearance outline)
				(anchor circle)
			)
			(primitives
				(gr_poly
					(pts
						(arc
							(start -0.1778 -0.2794)
							(mid -0.249642 -0.249642)
							(end -0.2794 -0.1778)
						)
						(arc
							(start -0.2794 0.1778)
							(mid -0.249642 0.249642)
							(end -0.1778 0.2794)
						)
						(arc
							(start 0.1778 0.2794)
							(mid 0.249642 0.249642)
							(end 0.2794 0.1778)
						)
						(arc
							(start 0.2794 -0.1778)
							(mid 0.249642 -0.249642)
							(end 0.1778 -0.2794)
						)
					)
					(width 0)
					(fill yes)
				)
			)
		)
		(pad "2" smd custom
			(at 0 0.4445 90)
			(size 0.1397 0.1397)
			(layers "F.Cu" "F.Mask" "F.Paste")
			(net "GND")
			(options
				(clearance outline)
				(anchor circle)
			)
			(primitives
				(gr_poly
					(pts
						(arc
							(start -0.1778 -0.2794)
							(mid -0.249642 -0.249642)
							(end -0.2794 -0.1778)
						)
						(arc
							(start -0.2794 0.1778)
							(mid -0.249642 0.249642)
							(end -0.1778 0.2794)
						)
						(arc
							(start 0.1778 0.2794)
							(mid 0.249642 0.249642)
							(end 0.2794 0.1778)
						)
						(arc
							(start 0.2794 -0.1778)
							(mid 0.249642 -0.249642)
							(end 0.1778 -0.2794)
						)
					)
					(width 0)
					(fill yes)
				)
			)
		)
	)
	(footprint ""
		(layer "F.Cu")
		(at 426.72 -128.651)
		(property "Reference" "R565"
			(at 0 0 0)
			(layer "F.SilkS")
			(hide yes)
			(effects
				(font
					(size 1.27 1.27)
				)
			)
		)
		(property "Value" "4K7R2F-GP"
			(at 0.064008 -3.993896 0)
			(unlocked yes)
			(layer "F.Fab")
			(hide yes)
			(effects
				(font
					(size 1.016 1.016)
					(thickness 0.1524)
				)
			)
		)
		(property "Device Type" "R402H16"
			(at 0.064008 -5.517896 0)
			(unlocked yes)
			(layer "F.Fab")
			(hide yes)
			(effects
				(font
					(size 1.016 1.016)
					(thickness 0.1524)
				)
			)
		)
		(duplicate_pad_numbers_are_jumpers no)
		(fp_line
			(start -0.508 -0.9398)
			(end -0.508 0.9398)
			(stroke
				(width 0.1524)
				(type default)
			)
			(layer "F.SilkS")
		)
		(fp_line
			(start 0.508 -0.9398)
			(end -0.508 -0.9398)
			(stroke
				(width 0.1524)
				(type default)
			)
			(layer "F.SilkS")
		)
		(fp_rect
			(start -0.508 0.9398)
			(end 0.508 -0.9398)
			(stroke
				(width 0)
				(type default)
			)
			(fill no)
			(layer "F.CrtYd")
		)
		(fp_rect
			(start -0.508 0.9398)
			(end 0.508 -0.9398)
			(stroke
				(width 0)
				(type default)
			)
			(fill no)
			(layer "F.Fab")
		)
		(pad "1" smd custom
			(at 0 -0.4445)
			(size 0.1397 0.1397)
			(layers "F.Cu" "F.Mask" "F.Paste")
			(net "SW_PWR_R_HDD21")
			(options
				(clearance outline)
				(anchor circle)
			)
			(primitives
				(gr_poly
					(pts
						(arc
							(start -0.1778 -0.2794)
							(mid -0.249642 -0.249642)
							(end -0.2794 -0.1778)
						)
						(arc
							(start -0.2794 0.1778)
							(mid -0.249642 0.249642)
							(end -0.1778 0.2794)
						)
						(arc
							(start 0.1778 0.2794)
							(mid 0.249642 0.249642)
							(end 0.2794 0.1778)
						)
						(arc
							(start 0.2794 -0.1778)
							(mid 0.249642 -0.249642)
							(end 0.1778 -0.2794)
						)
					)
					(width 0)
					(fill yes)
				)
			)
		)
		(pad "2" smd custom
			(at 0 0.4445)
			(size 0.1397 0.1397)
			(layers "F.Cu" "F.Mask" "F.Paste")
			(net "GND")
			(options
				(clearance outline)
				(anchor circle)
			)
			(primitives
				(gr_poly
					(pts
						(arc
							(start -0.1778 -0.2794)
							(mid -0.249642 -0.249642)
							(end -0.2794 -0.1778)
						)
						(arc
							(start -0.2794 0.1778)
							(mid -0.249642 0.249642)
							(end -0.1778 0.2794)
						)
						(arc
							(start 0.1778 0.2794)
							(mid 0.249642 0.249642)
							(end 0.2794 0.1778)
						)
						(arc
							(start 0.2794 -0.1778)
							(mid 0.249642 -0.249642)
							(end 0.1778 -0.2794)
						)
					)
					(width 0)
					(fill yes)
				)
			)
		)
	)
	(footprint ""
		(layer "F.Cu")
		(at 431.546 -246.761 180)
		(property "Reference" "R312"
			(at 0 0 180)
			(layer "F.SilkS")
			(hide yes)
			(effects
				(font
					(size 1.27 1.27)
				)
			)
		)
		(property "Value" "4K7R2J-2-GP"
			(at 0.064008 -3.993896 180)
			(unlocked yes)
			(layer "F.Fab")
			(hide yes)
			(effects
				(font
					(size 1.016 1.016)
					(thickness 0.1524)
				)
			)
		)
		(property "Device Type" "R402H16"
			(at 0.064008 -5.517896 180)
			(unlocked yes)
			(layer "F.Fab")
			(hide yes)
			(effects
				(font
					(size 1.016 1.016)
					(thickness 0.1524)
				)
			)
		)
		(duplicate_pad_numbers_are_jumpers no)
		(fp_line
			(start 0.508 -0.9398)
			(end -0.508 -0.9398)
			(stroke
				(width 0.1524)
				(type default)
			)
			(layer "F.SilkS")
		)
		(fp_line
			(start -0.508 -0.9398)
			(end -0.508 0.9398)
			(stroke
				(width 0.1524)
				(type default)
			)
			(layer "F.SilkS")
		)
		(fp_rect
			(start -0.508 0.9398)
			(end 0.508 -0.9398)
			(stroke
				(width 0)
				(type default)
			)
			(fill no)
			(layer "F.CrtYd")
		)
		(fp_rect
			(start -0.508 0.9398)
			(end 0.508 -0.9398)
			(stroke
				(width 0)
				(type default)
			)
			(fill no)
			(layer "F.Fab")
		)
		(pad "1" smd custom
			(at 0 -0.4445 180)
			(size 0.1397 0.1397)
			(layers "F.Cu" "F.Mask" "F.Paste")
			(net "P12V_B")
			(options
				(clearance outline)
				(anchor circle)
			)
			(primitives
				(gr_poly
					(pts
						(arc
							(start -0.1778 -0.2794)
							(mid -0.249642 -0.249642)
							(end -0.2794 -0.1778)
						)
						(arc
							(start -0.2794 0.1778)
							(mid -0.249642 0.249642)
							(end -0.1778 0.2794)
						)
						(arc
							(start 0.1778 0.2794)
							(mid 0.249642 0.249642)
							(end 0.2794 0.1778)
						)
						(arc
							(start 0.2794 -0.1778)
							(mid 0.249642 -0.249642)
							(end 0.1778 -0.2794)
						)
					)
					(width 0)
					(fill yes)
				)
			)
		)
		(pad "2" smd custom
			(at 0 0.4445 180)
			(size 0.1397 0.1397)
			(layers "F.Cu" "F.Mask" "F.Paste")
			(net "SW_HDD_R9")
			(options
				(clearance outline)
				(anchor circle)
			)
			(primitives
				(gr_poly
					(pts
						(arc
							(start -0.1778 -0.2794)
							(mid -0.249642 -0.249642)
							(end -0.2794 -0.1778)
						)
						(arc
							(start -0.2794 0.1778)
							(mid -0.249642 0.249642)
							(end -0.1778 0.2794)
						)
						(arc
							(start 0.1778 0.2794)
							(mid 0.249642 0.249642)
							(end 0.2794 0.1778)
						)
						(arc
							(start 0.2794 -0.1778)
							(mid 0.249642 -0.249642)
							(end 0.1778 -0.2794)
						)
					)
					(width 0)
					(fill yes)
				)
			)
		)
	)
)
